#ISCELL
  mstr_misc dns *
  *
#ISCELL
  pure_quanta quanta_title_block_c *
  *
#ISCELL
  logical_power universal_gnd *
  page325_i1
#ISCELL
  standard offpage *
  page325_i10
#CELL
  pure_quanta q_cap *
  page325_i11
#CELL
  pure_quanta q_res *
  page325_i12
#CELL
  pure_quanta q_res *
  page325_i13
#CELL
  pure_quanta q_res *
  page325_i14
#ISCELL
  standard offpage *
  page325_i15
#CELL
  pure_quanta q_res *
  page325_i16
#CELL
  pure_quanta mp5991gluz *
  page325_i17
#ISCELL
  logical_power universal_power *
  page325_i18
#CELL
  pure_quanta q_cap *
  page325_i19
#CELL
  pure_quanta q_cap *
  page325_i2
#ISCELL
  logical_power universal_gnd *
  page325_i20
#CELL
  pure_quanta q_res *
  page325_i21
#ISCELL
  logical_power universal_gnd *
  page325_i22
#CELL
  pure_quanta q_cap *
  page325_i23
#ISCELL
  standard offpage *
  page325_i24
#ISCELL
  logical_power universal_gnd *
  page325_i25
#ISCELL
  standard offpage *
  page325_i26
#ISCELL
  standard offpage *
  page325_i27
#ISCELL
  logical_power universal_power *
  page325_i28
#CELL
  pure_quanta q_cap *
  page325_i29
#ISCELL
  logical_power universal_gnd *
  page325_i3
#CELL
  pure_quanta q_res *
  page325_i30
#ISCELL
  standard offpage *
  page325_i31
#CELL
  pure_quanta q_res *
  page325_i32
#CELL
  pure_quanta q_res *
  page325_i33
#CELL
  pure_quanta q_res *
  page325_i34
#CELL
  pure_quanta mp5991gluz *
  page325_i35
#ISCELL
  logical_power universal_power *
  page325_i36
#ISCELL
  logical_power universal_gnd *
  page325_i37
#CELL
  pure_quanta q_cap *
  page325_i38
#CELL
  pure_quanta q_res *
  page325_i39
#CELL
  pure_quanta q_cap *
  page325_i4
#CELL
  pure_quanta q_res *
  page325_i40
#ISCELL
  logical_power universal_power *
  page325_i41
#ISCELL
  standard offpage *
  page325_i42
#ISCELL
  standard offpage *
  page325_i43
#ISCELL
  standard offpage *
  page325_i44
#ISCELL
  standard offpage *
  page325_i45
#ISCELL
  standard offpage *
  page325_i46
#ISCELL
  logical_power universal_gnd *
  page325_i47
#CELL
  pure_quanta q_cap *
  page325_i48
#CELL
  pure_quanta q_res *
  page325_i49
#CELL
  pure_quanta q_res *
  page325_i5
#CELL
  pure_quanta q_res *
  page325_i50
#ISCELL
  logical_power universal_power *
  page325_i51
#ISCELL
  standard offpage *
  page325_i52
#ISCELL
  standard offpage *
  page325_i53
#ISCELL
  standard offpage *
  page325_i54
#ISCELL
  standard offpage *
  page325_i55
#ISCELL
  standard offpage *
  page325_i56
#ISCELL
  logical_power universal_power *
  page325_i6
#ISCELL
  standard offpage *
  page325_i7
#ISCELL
  logical_power universal_gnd *
  page325_i8
#ISCELL
  standard offpage *
  page325_i9
